(kicad_pcb
	(version 20260206)
	(generator "pcbnew")
	(generator_version "10.0")
	(general
		(thickness 1.6)
		(legacy_teardrops no)
	)
	(paper "A4")
	(title_block
		(title "Wiwynn_Tioga_Pass_MB.brd")
		(comment 1 "Tioga Pass / footprint 1441 of 4770 (J4G3), pads 124-243 of 291")
	)
	(layers
		(0 "F.Cu" signal "TOP")
		(4 "In1.Cu" signal "L2GND")
		(6 "In2.Cu" signal "L3")
		(8 "In3.Cu" signal "L4GND")
		(10 "In4.Cu" signal "L5")
		(12 "In5.Cu" signal "L6GND")
		(14 "In6.Cu" signal "L7VCC")
		(16 "In7.Cu" signal "L8VCC")
		(18 "In8.Cu" signal "L9GND")
		(20 "In9.Cu" signal "L10")
		(22 "In10.Cu" signal "L11GND")
		(24 "In11.Cu" signal "L12")
		(26 "In12.Cu" signal "L13GND")
		(2 "B.Cu" signal "BOTTOM")
		(9 "F.Adhes" user "F.Adhesive")
		(11 "B.Adhes" user "B.Adhesive")
		(13 "F.Paste" user "Package Geometry/Pastemask Top")
		(15 "B.Paste" user "Package Geometry/Pastemask Bottom")
		(5 "F.SilkS" user "Ref Des/Silkscreen Top")
		(7 "B.SilkS" user "Ref Des/Silkscreen Bottom")
		(1 "F.Mask" user "Board Geometry/Soldermask Top")
		(3 "B.Mask" user "Board Geometry/Soldermask Bottom")
		(17 "Dwgs.User" user "User.Drawings")
		(19 "Cmts.User" user "User.Comments")
		(21 "Eco1.User" user "User.Eco1")
		(23 "Eco2.User" user "User.Eco2")
		(25 "Edge.Cuts" user "Board Geometry/Outline")
		(27 "Margin" user)
		(31 "F.CrtYd" user "Package Geometry/Place Bound Top")
		(29 "B.CrtYd" user "Package Geometry/Place Bound Bottom")
		(35 "F.Fab" user "Ref Des/Assembly Top")
		(33 "B.Fab" user "Ref Des/Assembly Bottom")
	)
	(footprint ""
		(layer "F.Cu")
		(at 194.700398 3.778758 90)
		(property "Reference" "J4G3"
			(at 6.800088 37.20211 0)
			(unlocked yes)
			(layer "F.SilkS")
			(effects
				(font
					(size 0.7874 0.5842)
					(thickness 0.1524)
				)
				(justify left)
			)
		)
		(property "Value" ""
			(at 0 0 90)
			(layer "F.Fab")
			(effects
				(font
					(size 1.27 1.27)
				)
			)
		)
		(duplicate_pad_numbers_are_jumpers no)
		(pad "121" smd rect
			(at 0 107.100116 90)
			(size 1.8034 0.508)
			(layers "F.Cu" "F.Mask" "F.Paste")
			(net "M_C_DQS_DP<15>")
		)
		(pad "122" smd rect
			(at 0 107.95 90)
			(size 1.8034 0.508)
			(layers "F.Cu" "F.Mask" "F.Paste")
			(net "M_C_DQS_DN<15>")
		)
		(pad "123" smd rect
			(at 0 108.799884 90)
			(size 1.8034 0.508)
			(layers "F.Cu" "F.Mask" "F.Paste")
			(net "GND")
		)
		(pad "124" smd rect
			(at 0 109.650022 90)
			(size 1.8034 0.508)
			(layers "F.Cu" "F.Mask" "F.Paste")
			(net "M_C_DQ<55>")
		)
		(pad "125" smd rect
			(at 0 110.499906 90)
			(size 1.8034 0.508)
			(layers "F.Cu" "F.Mask" "F.Paste")
			(net "GND")
		)
		(pad "126" smd rect
			(at 0 111.350044 90)
			(size 1.8034 0.508)
			(layers "F.Cu" "F.Mask" "F.Paste")
			(net "M_C_DQ<51>")
		)
		(pad "127" smd rect
			(at 0 112.199928 90)
			(size 1.8034 0.508)
			(layers "F.Cu" "F.Mask" "F.Paste")
			(net "GND")
		)
		(pad "128" smd rect
			(at 0 113.050066 90)
			(size 1.8034 0.508)
			(layers "F.Cu" "F.Mask" "F.Paste")
			(net "M_C_DQ<61>")
		)
		(pad "129" smd rect
			(at 0 113.89995 90)
			(size 1.8034 0.508)
			(layers "F.Cu" "F.Mask" "F.Paste")
			(net "GND")
		)
		(pad "130" smd rect
			(at 0 114.750088 90)
			(size 1.8034 0.508)
			(layers "F.Cu" "F.Mask" "F.Paste")
			(net "M_C_DQ<57>")
		)
		(pad "131" smd rect
			(at 0 115.599972 90)
			(size 1.8034 0.508)
			(layers "F.Cu" "F.Mask" "F.Paste")
			(net "GND")
		)
		(pad "132" smd rect
			(at 0 116.45011 90)
			(size 1.8034 0.508)
			(layers "F.Cu" "F.Mask" "F.Paste")
			(net "M_C_DQS_DP<16>")
		)
		(pad "133" smd rect
			(at 0 117.299994 90)
			(size 1.8034 0.508)
			(layers "F.Cu" "F.Mask" "F.Paste")
			(net "M_C_DQS_DN<16>")
		)
		(pad "134" smd rect
			(at 0 118.149878 90)
			(size 1.8034 0.508)
			(layers "F.Cu" "F.Mask" "F.Paste")
			(net "GND")
		)
		(pad "135" smd rect
			(at 0 119.000016 90)
			(size 1.8034 0.508)
			(layers "F.Cu" "F.Mask" "F.Paste")
			(net "M_C_DQ<63>")
		)
		(pad "136" smd rect
			(at 0 119.8499 90)
			(size 1.8034 0.508)
			(layers "F.Cu" "F.Mask" "F.Paste")
			(net "GND")
		)
		(pad "137" smd rect
			(at 0 120.700038 90)
			(size 1.8034 0.508)
			(layers "F.Cu" "F.Mask" "F.Paste")
			(net "M_C_DQ<59>")
		)
		(pad "138" smd rect
			(at 0 121.549922 90)
			(size 1.8034 0.508)
			(layers "F.Cu" "F.Mask" "F.Paste")
			(net "GND")
		)
		(pad "139" smd rect
			(at 0 122.40006 90)
			(size 1.8034 0.508)
			(layers "F.Cu" "F.Mask" "F.Paste")
			(net "GND")
		)
		(pad "140" smd rect
			(at 0 123.249944 90)
			(size 1.8034 0.508)
			(layers "F.Cu" "F.Mask" "F.Paste")
			(net "GND")
		)
		(pad "141" smd rect
			(at 0 124.100082 90)
			(size 1.8034 0.508)
			(layers "F.Cu" "F.Mask" "F.Paste")
			(net "SMB_DDR_ABC_VPP_SCL")
		)
		(pad "142" smd rect
			(at 0 124.949966 90)
			(size 1.8034 0.508)
			(layers "F.Cu" "F.Mask" "F.Paste")
			(net "PVPP_ABC")
		)
		(pad "143" smd rect
			(at 0 125.800104 90)
			(size 1.8034 0.508)
			(layers "F.Cu" "F.Mask" "F.Paste")
			(net "PVPP_ABC")
		)
		(pad "144" smd rect
			(at 0 126.649988 90)
			(size 1.8034 0.508)
			(layers "F.Cu" "F.Mask" "F.Paste")
			(net "TP_CH_C_DIMM_C0_RFU_2")
		)
		(pad "145" smd rect
			(at 4.59994 0 90)
			(size 1.8034 0.508)
			(layers "F.Cu" "F.Mask" "F.Paste")
			(net "P12V_NVDIMM_ABC")
		)
		(pad "146" smd rect
			(at 4.59994 0.849884 90)
			(size 1.8034 0.508)
			(layers "F.Cu" "F.Mask" "F.Paste")
			(net "M_C_VREF")
		)
		(pad "147" smd rect
			(at 4.59994 1.700022 90)
			(size 1.8034 0.508)
			(layers "F.Cu" "F.Mask" "F.Paste")
			(net "GND")
		)
		(pad "148" smd rect
			(at 4.59994 2.549906 90)
			(size 1.8034 0.508)
			(layers "F.Cu" "F.Mask" "F.Paste")
			(net "M_C_DQ<4>")
		)
		(pad "149" smd rect
			(at 4.59994 3.400044 90)
			(size 1.8034 0.508)
			(layers "F.Cu" "F.Mask" "F.Paste")
			(net "GND")
		)
		(pad "150" smd rect
			(at 4.59994 4.249928 90)
			(size 1.8034 0.508)
			(layers "F.Cu" "F.Mask" "F.Paste")
			(net "M_C_DQ<0>")
		)
		(pad "151" smd rect
			(at 4.59994 5.100066 90)
			(size 1.8034 0.508)
			(layers "F.Cu" "F.Mask" "F.Paste")
			(net "GND")
		)
		(pad "152" smd rect
			(at 4.59994 5.94995 90)
			(size 1.8034 0.508)
			(layers "F.Cu" "F.Mask" "F.Paste")
			(net "M_C_DQS_DN<0>")
		)
		(pad "153" smd rect
			(at 4.59994 6.800088 90)
			(size 1.8034 0.508)
			(layers "F.Cu" "F.Mask" "F.Paste")
			(net "M_C_DQS_DP<0>")
		)
		(pad "154" smd rect
			(at 4.59994 7.649972 90)
			(size 1.8034 0.508)
			(layers "F.Cu" "F.Mask" "F.Paste")
			(net "GND")
		)
		(pad "155" smd rect
			(at 4.59994 8.50011 90)
			(size 1.8034 0.508)
			(layers "F.Cu" "F.Mask" "F.Paste")
			(net "M_C_DQ<6>")
		)
		(pad "156" smd rect
			(at 4.59994 9.349994 90)
			(size 1.8034 0.508)
			(layers "F.Cu" "F.Mask" "F.Paste")
			(net "GND")
		)
		(pad "157" smd rect
			(at 4.59994 10.199878 90)
			(size 1.8034 0.508)
			(layers "F.Cu" "F.Mask" "F.Paste")
			(net "M_C_DQ<2>")
		)
		(pad "158" smd rect
			(at 4.59994 11.050016 90)
			(size 1.8034 0.508)
			(layers "F.Cu" "F.Mask" "F.Paste")
			(net "GND")
		)
		(pad "159" smd rect
			(at 4.59994 11.8999 90)
			(size 1.8034 0.508)
			(layers "F.Cu" "F.Mask" "F.Paste")
			(net "M_C_DQ<12>")
		)
		(pad "160" smd rect
			(at 4.59994 12.750038 90)
			(size 1.8034 0.508)
			(layers "F.Cu" "F.Mask" "F.Paste")
			(net "GND")
		)
		(pad "161" smd rect
			(at 4.59994 13.599922 90)
			(size 1.8034 0.508)
			(layers "F.Cu" "F.Mask" "F.Paste")
			(net "M_C_DQ<8>")
		)
		(pad "162" smd rect
			(at 4.59994 14.45006 90)
			(size 1.8034 0.508)
			(layers "F.Cu" "F.Mask" "F.Paste")
			(net "GND")
		)
		(pad "163" smd rect
			(at 4.59994 15.299944 90)
			(size 1.8034 0.508)
			(layers "F.Cu" "F.Mask" "F.Paste")
			(net "M_C_DQS_DN<1>")
		)
		(pad "164" smd rect
			(at 4.59994 16.150082 90)
			(size 1.8034 0.508)
			(layers "F.Cu" "F.Mask" "F.Paste")
			(net "M_C_DQS_DP<1>")
		)
		(pad "165" smd rect
			(at 4.59994 16.999966 90)
			(size 1.8034 0.508)
			(layers "F.Cu" "F.Mask" "F.Paste")
			(net "GND")
		)
		(pad "166" smd rect
			(at 4.59994 17.850104 90)
			(size 1.8034 0.508)
			(layers "F.Cu" "F.Mask" "F.Paste")
			(net "M_C_DQ<14>")
		)
		(pad "167" smd rect
			(at 4.59994 18.699988 90)
			(size 1.8034 0.508)
			(layers "F.Cu" "F.Mask" "F.Paste")
			(net "GND")
		)
		(pad "168" smd rect
			(at 4.59994 19.550126 90)
			(size 1.8034 0.508)
			(layers "F.Cu" "F.Mask" "F.Paste")
			(net "M_C_DQ<10>")
		)
		(pad "169" smd rect
			(at 4.59994 20.40001 90)
			(size 1.8034 0.508)
			(layers "F.Cu" "F.Mask" "F.Paste")
			(net "GND")
		)
		(pad "170" smd rect
			(at 4.59994 21.249894 90)
			(size 1.8034 0.508)
			(layers "F.Cu" "F.Mask" "F.Paste")
			(net "M_C_DQ<20>")
		)
		(pad "171" smd rect
			(at 4.59994 22.100032 90)
			(size 1.8034 0.508)
			(layers "F.Cu" "F.Mask" "F.Paste")
			(net "GND")
		)
		(pad "172" smd rect
			(at 4.59994 22.949916 90)
			(size 1.8034 0.508)
			(layers "F.Cu" "F.Mask" "F.Paste")
			(net "M_C_DQ<16>")
		)
		(pad "173" smd rect
			(at 4.59994 23.800054 90)
			(size 1.8034 0.508)
			(layers "F.Cu" "F.Mask" "F.Paste")
			(net "GND")
		)
		(pad "174" smd rect
			(at 4.59994 24.649938 90)
			(size 1.8034 0.508)
			(layers "F.Cu" "F.Mask" "F.Paste")
			(net "M_C_DQS_DN<2>")
		)
		(pad "175" smd rect
			(at 4.59994 25.500076 90)
			(size 1.8034 0.508)
			(layers "F.Cu" "F.Mask" "F.Paste")
			(net "M_C_DQS_DP<2>")
		)
		(pad "176" smd rect
			(at 4.59994 26.34996 90)
			(size 1.8034 0.508)
			(layers "F.Cu" "F.Mask" "F.Paste")
			(net "GND")
		)
		(pad "177" smd rect
			(at 4.59994 27.200098 90)
			(size 1.8034 0.508)
			(layers "F.Cu" "F.Mask" "F.Paste")
			(net "M_C_DQ<22>")
		)
		(pad "178" smd rect
			(at 4.59994 28.049982 90)
			(size 1.8034 0.508)
			(layers "F.Cu" "F.Mask" "F.Paste")
			(net "GND")
		)
		(pad "179" smd rect
			(at 4.59994 28.90012 90)
			(size 1.8034 0.508)
			(layers "F.Cu" "F.Mask" "F.Paste")
			(net "M_C_DQ<18>")
		)
		(pad "180" smd rect
			(at 4.59994 29.750004 90)
			(size 1.8034 0.508)
			(layers "F.Cu" "F.Mask" "F.Paste")
			(net "GND")
		)
		(pad "181" smd rect
			(at 4.59994 30.599888 90)
			(size 1.8034 0.508)
			(layers "F.Cu" "F.Mask" "F.Paste")
			(net "M_C_DQ<28>")
		)
		(pad "182" smd rect
			(at 4.59994 31.450026 90)
			(size 1.8034 0.508)
			(layers "F.Cu" "F.Mask" "F.Paste")
			(net "GND")
		)
		(pad "183" smd rect
			(at 4.59994 32.29991 90)
			(size 1.8034 0.508)
			(layers "F.Cu" "F.Mask" "F.Paste")
			(net "M_C_DQ<24>")
		)
		(pad "184" smd rect
			(at 4.59994 33.150048 90)
			(size 1.8034 0.508)
			(layers "F.Cu" "F.Mask" "F.Paste")
			(net "GND")
		)
		(pad "185" smd rect
			(at 4.59994 33.999932 90)
			(size 1.8034 0.508)
			(layers "F.Cu" "F.Mask" "F.Paste")
			(net "M_C_DQS_DN<3>")
		)
		(pad "186" smd rect
			(at 4.59994 34.85007 90)
			(size 1.8034 0.508)
			(layers "F.Cu" "F.Mask" "F.Paste")
			(net "M_C_DQS_DP<3>")
		)
		(pad "187" smd rect
			(at 4.59994 35.699954 90)
			(size 1.8034 0.508)
			(layers "F.Cu" "F.Mask" "F.Paste")
			(net "GND")
		)
		(pad "188" smd rect
			(at 4.59994 36.550092 90)
			(size 1.8034 0.508)
			(layers "F.Cu" "F.Mask" "F.Paste")
			(net "M_C_DQ<30>")
		)
		(pad "189" smd rect
			(at 4.59994 37.399976 90)
			(size 1.8034 0.508)
			(layers "F.Cu" "F.Mask" "F.Paste")
			(net "GND")
		)
		(pad "190" smd rect
			(at 4.59994 38.250114 90)
			(size 1.8034 0.508)
			(layers "F.Cu" "F.Mask" "F.Paste")
			(net "M_C_DQ<26>")
		)
		(pad "191" smd rect
			(at 4.59994 39.099998 90)
			(size 1.8034 0.508)
			(layers "F.Cu" "F.Mask" "F.Paste")
			(net "GND")
		)
		(pad "192" smd rect
			(at 4.59994 39.949882 90)
			(size 1.8034 0.508)
			(layers "F.Cu" "F.Mask" "F.Paste")
			(net "M_C_ECC<4>")
		)
		(pad "193" smd rect
			(at 4.59994 40.80002 90)
			(size 1.8034 0.508)
			(layers "F.Cu" "F.Mask" "F.Paste")
			(net "GND")
		)
		(pad "194" smd rect
			(at 4.59994 41.649904 90)
			(size 1.8034 0.508)
			(layers "F.Cu" "F.Mask" "F.Paste")
			(net "M_C_ECC<0>")
		)
		(pad "195" smd rect
			(at 4.59994 42.500042 90)
			(size 1.8034 0.508)
			(layers "F.Cu" "F.Mask" "F.Paste")
			(net "GND")
		)
		(pad "196" smd rect
			(at 4.59994 43.349926 90)
			(size 1.8034 0.508)
			(layers "F.Cu" "F.Mask" "F.Paste")
			(net "M_C_DQS_DN<8>")
		)
		(pad "197" smd rect
			(at 4.59994 44.200064 90)
			(size 1.8034 0.508)
			(layers "F.Cu" "F.Mask" "F.Paste")
			(net "M_C_DQS_DP<8>")
		)
		(pad "198" smd rect
			(at 4.59994 45.049948 90)
			(size 1.8034 0.508)
			(layers "F.Cu" "F.Mask" "F.Paste")
			(net "GND")
		)
		(pad "199" smd rect
			(at 4.59994 45.900086 90)
			(size 1.8034 0.508)
			(layers "F.Cu" "F.Mask" "F.Paste")
			(net "M_C_ECC<6>")
		)
		(pad "200" smd rect
			(at 4.59994 46.74997 90)
			(size 1.8034 0.508)
			(layers "F.Cu" "F.Mask" "F.Paste")
			(net "GND")
		)
		(pad "201" smd rect
			(at 4.59994 47.600108 90)
			(size 1.8034 0.508)
			(layers "F.Cu" "F.Mask" "F.Paste")
			(net "M_C_ECC<2>")
		)
		(pad "202" smd rect
			(at 4.59994 48.449992 90)
			(size 1.8034 0.508)
			(layers "F.Cu" "F.Mask" "F.Paste")
			(net "GND")
		)
		(pad "203" smd rect
			(at 4.59994 49.299876 90)
			(size 1.8034 0.508)
			(layers "F.Cu" "F.Mask" "F.Paste")
			(net "M_C_CKE<1>")
		)
		(pad "204" smd rect
			(at 4.59994 50.150014 90)
			(size 1.8034 0.508)
			(layers "F.Cu" "F.Mask" "F.Paste")
			(net "PVDDQ_ABC")
		)
		(pad "205" smd rect
			(at 4.59994 50.999898 90)
			(size 1.8034 0.508)
			(layers "F.Cu" "F.Mask" "F.Paste")
			(net "TP_CH_C_DIMM_C0_RFU_0")
		)
		(pad "206" smd rect
			(at 4.59994 51.850036 90)
			(size 1.8034 0.508)
			(layers "F.Cu" "F.Mask" "F.Paste")
			(net "PVDDQ_ABC")
		)
		(pad "207" smd rect
			(at 4.59994 52.69992 90)
			(size 1.8034 0.508)
			(layers "F.Cu" "F.Mask" "F.Paste")
			(net "M_C_BG<1>")
		)
		(pad "208" smd rect
			(at 4.59994 53.550058 90)
			(size 1.8034 0.508)
			(layers "F.Cu" "F.Mask" "F.Paste")
			(net "M_C_ALERT_N")
		)
		(pad "209" smd rect
			(at 4.59994 54.399942 90)
			(size 1.8034 0.508)
			(layers "F.Cu" "F.Mask" "F.Paste")
			(net "PVDDQ_ABC")
		)
		(pad "210" smd rect
			(at 4.59994 55.25008 90)
			(size 1.8034 0.508)
			(layers "F.Cu" "F.Mask" "F.Paste")
			(net "M_C_MA<11>")
		)
		(pad "211" smd rect
			(at 4.59994 56.099964 90)
			(size 1.8034 0.508)
			(layers "F.Cu" "F.Mask" "F.Paste")
			(net "M_C_MA<7>")
		)
		(pad "212" smd rect
			(at 4.59994 56.950102 90)
			(size 1.8034 0.508)
			(layers "F.Cu" "F.Mask" "F.Paste")
			(net "PVDDQ_ABC")
		)
		(pad "213" smd rect
			(at 4.59994 57.799986 90)
			(size 1.8034 0.508)
			(layers "F.Cu" "F.Mask" "F.Paste")
			(net "M_C_MA<5>")
		)
		(pad "214" smd rect
			(at 4.59994 58.650124 90)
			(size 1.8034 0.508)
			(layers "F.Cu" "F.Mask" "F.Paste")
			(net "M_C_MA<4>")
		)
		(pad "215" smd rect
			(at 4.59994 59.500008 90)
			(size 1.8034 0.508)
			(layers "F.Cu" "F.Mask" "F.Paste")
			(net "PVDDQ_ABC")
		)
		(pad "216" smd rect
			(at 4.59994 60.349892 90)
			(size 1.8034 0.508)
			(layers "F.Cu" "F.Mask" "F.Paste")
			(net "M_C_MA<2>")
		)
		(pad "217" smd rect
			(at 4.59994 61.20003 90)
			(size 1.8034 0.508)
			(layers "F.Cu" "F.Mask" "F.Paste")
			(net "PVDDQ_ABC")
		)
		(pad "218" smd rect
			(at 4.59994 62.049914 90)
			(size 1.8034 0.508)
			(layers "F.Cu" "F.Mask" "F.Paste")
			(net "M_C_CLK_DP<1>")
		)
		(pad "219" smd rect
			(at 4.59994 62.900052 90)
			(size 1.8034 0.508)
			(layers "F.Cu" "F.Mask" "F.Paste")
			(net "M_C_CLK_DN<1>")
		)
		(pad "220" smd rect
			(at 4.59994 63.749936 90)
			(size 1.8034 0.508)
			(layers "F.Cu" "F.Mask" "F.Paste")
			(net "PVDDQ_ABC")
		)
		(pad "221" smd rect
			(at 4.59994 64.600074 90)
			(size 1.8034 0.508)
			(layers "F.Cu" "F.Mask" "F.Paste")
			(net "PVTT_ABC")
		)
		(pad "222" smd rect
			(at 4.59994 70.550024 90)
			(size 1.8034 0.508)
			(layers "F.Cu" "F.Mask" "F.Paste")
			(net "M_C_PAR")
		)
		(pad "223" smd rect
			(at 4.59994 71.399908 90)
			(size 1.8034 0.508)
			(layers "F.Cu" "F.Mask" "F.Paste")
			(net "PVDDQ_ABC")
		)
		(pad "224" smd rect
			(at 4.59994 72.250046 90)
			(size 1.8034 0.508)
			(layers "F.Cu" "F.Mask" "F.Paste")
			(net "M_C_BA<1>")
		)
		(pad "225" smd rect
			(at 4.59994 73.09993 90)
			(size 1.8034 0.508)
			(layers "F.Cu" "F.Mask" "F.Paste")
			(net "M_C_MA<10>")
		)
		(pad "226" smd rect
			(at 4.59994 73.950068 90)
			(size 1.8034 0.508)
			(layers "F.Cu" "F.Mask" "F.Paste")
			(net "PVDDQ_ABC")
		)
		(pad "227" smd rect
			(at 4.59994 74.799952 90)
			(size 1.8034 0.508)
			(layers "F.Cu" "F.Mask" "F.Paste")
			(net "TP_CH_C_DIMM_C0_RFU_1")
		)
		(pad "228" smd rect
			(at 4.59994 75.65009 90)
			(size 1.8034 0.508)
			(layers "F.Cu" "F.Mask" "F.Paste")
			(net "M_C_MA<14>")
		)
		(pad "229" smd rect
			(at 4.59994 76.499974 90)
			(size 1.8034 0.508)
			(layers "F.Cu" "F.Mask" "F.Paste")
			(net "PVDDQ_ABC")
		)
		(pad "230" smd rect
			(at 4.59994 77.350112 90)
			(size 1.8034 0.508)
			(layers "F.Cu" "F.Mask" "F.Paste")
			(net "FM_ADR_COMPLETE_ABC_N")
		)
		(pad "231" smd rect
			(at 4.59994 78.199996 90)
			(size 1.8034 0.508)
			(layers "F.Cu" "F.Mask" "F.Paste")
			(net "PVDDQ_ABC")
		)
		(pad "232" smd rect
			(at 4.59994 79.04988 90)
			(size 1.8034 0.508)
			(layers "F.Cu" "F.Mask" "F.Paste")
			(net "M_C_MA<13>")
		)
		(pad "233" smd rect
			(at 4.59994 79.900018 90)
			(size 1.8034 0.508)
			(layers "F.Cu" "F.Mask" "F.Paste")
			(net "PVDDQ_ABC")
		)
		(pad "234" smd rect
			(at 4.59994 80.749902 90)
			(size 1.8034 0.508)
			(layers "F.Cu" "F.Mask" "F.Paste")
			(net "M_C_MA<17>")
		)
		(pad "235" smd rect
			(at 4.59994 81.60004 90)
			(size 1.8034 0.508)
			(layers "F.Cu" "F.Mask" "F.Paste")
			(net "M_C_C<2>")
		)
		(pad "236" smd rect
			(at 4.59994 82.449924 90)
			(size 1.8034 0.508)
			(layers "F.Cu" "F.Mask" "F.Paste")
			(net "PVDDQ_ABC")
		)
		(pad "237" smd rect
			(at 4.59994 83.300062 90)
			(size 1.8034 0.508)
			(layers "F.Cu" "F.Mask" "F.Paste")
			(net "M_C_CS_N<3>")
		)
		(pad "238" smd rect
			(at 4.59994 84.149946 90)
			(size 1.8034 0.508)
			(layers "F.Cu" "F.Mask" "F.Paste")
			(net "PVPP_ABC")
		)
		(pad "239" smd rect
			(at 4.59994 85.000084 90)
			(size 1.8034 0.508)
			(layers "F.Cu" "F.Mask" "F.Paste")
			(net "GND")
		)
		(pad "240" smd rect
			(at 4.59994 85.849968 90)
			(size 1.8034 0.508)
			(layers "F.Cu" "F.Mask" "F.Paste")
			(net "M_C_DQ<36>")
		)
	)
)
